(kicad_pcb
	(version 20241229)
	(generator "pcbnew")
	(generator_version "9.0")
	(general
		(thickness 1.62)
		(legacy_teardrops no)
	)
	(paper "A3")
	(title_block
		(title "COM Express 7 Baseboard")
		(date "2025-02-04")
		(rev "1.1.2")
		(company "Antmicro Ltd")
		(comment 1 "www.antmicro.com")
		(comment 9 "footprints 387-391 of 802")
	)
	(layers
		(0 "F.Cu" signal)
		(4 "In1.Cu" signal)
		(6 "In2.Cu" signal)
		(8 "In3.Cu" signal)
		(10 "In4.Cu" signal)
		(12 "In5.Cu" signal)
		(14 "In6.Cu" signal)
		(2 "B.Cu" signal)
		(9 "F.Adhes" user "F.Adhesive")
		(11 "B.Adhes" user "B.Adhesive")
		(13 "F.Paste" user)
		(15 "B.Paste" user)
		(5 "F.SilkS" user "F.Silkscreen")
		(7 "B.SilkS" user "B.Silkscreen")
		(1 "F.Mask" user)
		(3 "B.Mask" user)
		(17 "Dwgs.User" user "User.Drawings")
		(19 "Cmts.User" user "User.Comments")
		(21 "Eco1.User" user "User.Eco1")
		(23 "Eco2.User" user "User.Eco2")
		(25 "Edge.Cuts" user)
		(27 "Margin" user)
		(31 "F.CrtYd" user "F.Courtyard")
		(29 "B.CrtYd" user "B.Courtyard")
		(35 "F.Fab" user)
		(33 "B.Fab" user)
	)
	(footprint "antmicro-footprints:R_0402_1005Metric"
		(layer "F.Cu")
		(at 179.35 103.87 90)
		(descr "Resistor SMD 0402")
		(tags "resistor SMD 0402")
		(property "Reference" "R122"
			(at 0.81 0.45 90)
			(layer "F.SilkS")
			(effects
				(font
					(size 0.7 0.7)
					(thickness 0.15)
				)
				(justify left bottom)
			)
		)
		(property "Value" "R_10k_0402"
			(at -1.011843 1.772047 90)
			(layer "F.Fab")
			(effects
				(font
					(size 0.7 0.7)
					(thickness 0.15)
				)
				(justify left bottom)
			)
		)
		(property "Datasheet" "https://www.bourns.com/docs/product-datasheets/cr.pdf"
			(at 0 0 90)
			(layer "F.Fab")
			(hide yes)
			(effects
				(font
					(size 1.27 1.27)
					(thickness 0.15)
				)
			)
		)
		(property "Author" "Antmicro"
			(at 283.22 -75.48 0)
			(layer "F.Fab")
			(hide yes)
			(effects
				(font
					(size 1 1)
					(thickness 0.15)
				)
			)
		)
		(property "License" "Apache-2.0"
			(at 283.22 -75.48 0)
			(layer "F.Fab")
			(hide yes)
			(effects
				(font
					(size 1 1)
					(thickness 0.15)
				)
			)
		)
		(property "MPN" "CR0402-FX-1002GLF"
			(at 283.22 -75.48 0)
			(layer "F.Fab")
			(hide yes)
			(effects
				(font
					(size 1 1)
					(thickness 0.15)
				)
			)
		)
		(property "Manufacturer" "Bourns"
			(at 283.22 -75.48 0)
			(layer "F.Fab")
			(hide yes)
			(effects
				(font
					(size 1 1)
					(thickness 0.15)
				)
			)
		)
		(property "Public" "False"
			(at 283.22 -75.48 0)
			(layer "F.Fab")
			(hide yes)
			(effects
				(font
					(size 1 1)
					(thickness 0.15)
				)
			)
		)
		(property "Tolerance" "1%"
			(at 283.22 -75.48 0)
			(layer "F.Fab")
			(hide yes)
			(effects
				(font
					(size 1 1)
					(thickness 0.15)
				)
			)
		)
		(property "Val" "10k"
			(at 283.22 -75.48 0)
			(layer "F.Fab")
			(hide yes)
			(effects
				(font
					(size 1 1)
					(thickness 0.15)
				)
			)
		)
		(sheetname "M.2 key M #1")
		(sheetfile "m2keym_low.kicad_sch")
		(attr smd)
		(fp_rect
			(start -0.925 -0.47)
			(end 0.925 0.47)
			(stroke
				(width 0.05)
				(type default)
			)
			(fill no)
			(layer "F.CrtYd")
		)
		(fp_rect
			(start -0.5 -0.25)
			(end 0.5 0.25)
			(stroke
				(width 0.15)
				(type solid)
			)
			(fill no)
			(layer "F.Fab")
		)
		(pad "1" smd roundrect
			(at -0.48 0 90)
			(size 0.59 0.64)
			(layers "F.Cu" "F.Mask" "F.Paste")
			(roundrect_rratio 0.25)
			(net 529 "/M.2 key M #1/~{CLKREQ}")
			(pintype "passive")
			(teardrops
				(best_length_ratio 0.2)
				(max_length 1)
				(best_width_ratio 0.9)
				(max_width 2)
				(curved_edges yes)
				(filter_ratio 0.9)
				(enabled yes)
				(allow_two_segments yes)
				(prefer_zone_connections yes)
			)
		)
		(pad "2" smd roundrect
			(at 0.48 0 90)
			(size 0.59 0.64)
			(layers "F.Cu" "F.Mask" "F.Paste")
			(roundrect_rratio 0.25)
			(net 2 "+3V3")
			(pintype "passive")
			(teardrops
				(best_length_ratio 0.2)
				(max_length 1)
				(best_width_ratio 0.9)
				(max_width 2)
				(curved_edges yes)
				(filter_ratio 0.9)
				(enabled yes)
				(allow_two_segments yes)
				(prefer_zone_connections yes)
			)
		)
	)
	(footprint "antmicro-footprints:TSSOP-8_3x3mm_P0.65mm"
		(layer "F.Cu")
		(at 234.970707 78.085)
		(property "Reference" "U29"
			(at -0.999999 2.725 0)
			(layer "F.SilkS")
			(effects
				(font
					(size 0.7 0.7)
					(thickness 0.15)
				)
				(justify left bottom)
			)
		)
		(property "Value" "NTS0102_TSSOP"
			(at 0 2.8 0)
			(layer "F.Fab")
			(effects
				(font
					(size 0.7 0.7)
					(thickness 0.15)
				)
				(justify left bottom)
			)
		)
		(property "Datasheet" "https://www.mouser.com/datasheet/2/302/NTS0102-1127324.pdf"
			(at 0 0 0)
			(layer "F.Fab")
			(hide yes)
			(effects
				(font
					(size 1.27 1.27)
					(thickness 0.15)
				)
			)
		)
		(property "Author" "Antmicro"
			(at 0 0 0)
			(layer "F.Fab")
			(hide yes)
			(effects
				(font
					(size 1 1)
					(thickness 0.15)
				)
			)
		)
		(property "License" "Apache-2.0"
			(at 0 0 0)
			(layer "F.Fab")
			(hide yes)
			(effects
				(font
					(size 1 1)
					(thickness 0.15)
				)
			)
		)
		(property "MPN" "NTS0102DP"
			(at 0 0 0)
			(layer "F.Fab")
			(hide yes)
			(effects
				(font
					(size 1 1)
					(thickness 0.15)
				)
			)
		)
		(property "Manufacturer" "NXP"
			(at 0 0 0)
			(layer "F.Fab")
			(hide yes)
			(effects
				(font
					(size 1 1)
					(thickness 0.15)
				)
			)
		)
		(sheetname "Misc")
		(sheetfile "misc.kicad_sch")
		(attr smd)
		(fp_line
			(start -1.55 1.561)
			(end 1.552 1.561)
			(stroke
				(width 0.15)
				(type solid)
			)
			(layer "F.SilkS")
		)
		(fp_line
			(start -1.525 -1.537)
			(end 1.552 -1.539)
			(stroke
				(width 0.15)
				(type solid)
			)
			(layer "F.SilkS")
		)
		(fp_circle
			(center -1.87 -1.4)
			(end -1.82 -1.4)
			(stroke
				(width 0.15)
				(type solid)
			)
			(fill yes)
			(layer "F.SilkS")
		)
		(fp_rect
			(start -3.15 -1.789)
			(end 3.15 1.811)
			(stroke
				(width 0.05)
				(type solid)
			)
			(fill no)
			(layer "F.CrtYd")
		)
		(fp_line
			(start -1.55 -0.937)
			(end -1.55 1.561)
			(stroke
				(width 0.15)
				(type solid)
			)
			(layer "F.Fab")
		)
		(fp_line
			(start -1.55 -0.937)
			(end -0.949 -1.539)
			(stroke
				(width 0.15)
				(type solid)
			)
			(layer "F.Fab")
		)
		(fp_line
			(start -1.55 1.561)
			(end 1.552 1.561)
			(stroke
				(width 0.15)
				(type solid)
			)
			(layer "F.Fab")
		)
		(fp_line
			(start -0.949 -1.539)
			(end 1.552 -1.539)
			(stroke
				(width 0.15)
				(type solid)
			)
			(layer "F.Fab")
		)
		(fp_line
			(start 1.552 -1.539)
			(end 1.552 1.561)
			(stroke
				(width 0.15)
				(type solid)
			)
			(layer "F.Fab")
		)
		(pad "1" smd roundrect
			(at -2.148 -0.962)
			(size 1.47 0.4)
			(layers "F.Cu" "F.Mask" "F.Paste")
			(roundrect_rratio 0.25)
			(net 284 "/Misc/PWM_{C5V}")
			(pinfunction "B_{2}")
			(pintype "bidirectional")
			(teardrops
				(best_length_ratio 0.2)
				(max_length 1)
				(best_width_ratio 0.9)
				(max_width 2)
				(curved_edges yes)
				(filter_ratio 0.9)
				(enabled yes)
				(allow_two_segments yes)
				(prefer_zone_connections yes)
			)
		)
		(pad "2" smd roundrect
			(at -2.148 -0.313)
			(size 1.47 0.4)
			(layers "F.Cu" "F.Mask" "F.Paste")
			(roundrect_rratio 0.25)
			(net 1 "GND")
			(pinfunction "GND")
			(pintype "power_in")
			(teardrops
				(best_length_ratio 0.2)
				(max_length 1)
				(best_width_ratio 0.9)
				(max_width 2)
				(curved_edges yes)
				(filter_ratio 0.9)
				(enabled yes)
				(allow_two_segments yes)
				(prefer_zone_connections yes)
			)
		)
		(pad "3" smd roundrect
			(at -2.148 0.338)
			(size 1.47 0.4)
			(layers "F.Cu" "F.Mask" "F.Paste")
			(roundrect_rratio 0.25)
			(net 2 "+3V3")
			(pinfunction "VCC_{A}")
			(pintype "power_in")
			(teardrops
				(best_length_ratio 0.2)
				(max_length 1)
				(best_width_ratio 0.9)
				(max_width 2)
				(curved_edges yes)
				(filter_ratio 0.9)
				(enabled yes)
				(allow_two_segments yes)
				(prefer_zone_connections yes)
			)
		)
		(pad "4" smd roundrect
			(at -2.148 0.987)
			(size 1.47 0.4)
			(layers "F.Cu" "F.Mask" "F.Paste")
			(roundrect_rratio 0.25)
			(net 400 "/Com Express 7 MGMT/FAN_PWM")
			(pinfunction "A_{2}")
			(pintype "bidirectional")
			(teardrops
				(best_length_ratio 0.2)
				(max_length 1)
				(best_width_ratio 0.9)
				(max_width 2)
				(curved_edges yes)
				(filter_ratio 0.9)
				(enabled yes)
				(allow_two_segments yes)
				(prefer_zone_connections yes)
			)
		)
		(pad "5" smd roundrect
			(at 2.151 0.987)
			(size 1.47 0.4)
			(layers "F.Cu" "F.Mask" "F.Paste")
			(roundrect_rratio 0.25)
			(net 401 "/Com Express 7 MGMT/FAM_TACH")
			(pinfunction "A_{1}")
			(pintype "bidirectional")
			(teardrops
				(best_length_ratio 0.2)
				(max_length 1)
				(best_width_ratio 0.9)
				(max_width 2)
				(curved_edges yes)
				(filter_ratio 0.9)
				(enabled yes)
				(allow_two_segments yes)
				(prefer_zone_connections yes)
			)
		)
		(pad "6" smd roundrect
			(at 2.151 0.338)
			(size 1.47 0.4)
			(layers "F.Cu" "F.Mask" "F.Paste")
			(roundrect_rratio 0.25)
			(net 2 "+3V3")
			(pinfunction "OE")
			(pintype "input")
			(teardrops
				(best_length_ratio 0.2)
				(max_length 1)
				(best_width_ratio 0.9)
				(max_width 2)
				(curved_edges yes)
				(filter_ratio 0.9)
				(enabled yes)
				(allow_two_segments yes)
				(prefer_zone_connections yes)
			)
		)
		(pad "7" smd roundrect
			(at 2.151 -0.313)
			(size 1.47 0.4)
			(layers "F.Cu" "F.Mask" "F.Paste")
			(roundrect_rratio 0.25)
			(net 52 "+5V")
			(pinfunction "VCC_{B}")
			(pintype "power_in")
			(teardrops
				(best_length_ratio 0.2)
				(max_length 1)
				(best_width_ratio 0.9)
				(max_width 2)
				(curved_edges yes)
				(filter_ratio 0.9)
				(enabled yes)
				(allow_two_segments yes)
				(prefer_zone_connections yes)
			)
		)
		(pad "8" smd roundrect
			(at 2.151 -0.962)
			(size 1.47 0.4)
			(layers "F.Cu" "F.Mask" "F.Paste")
			(roundrect_rratio 0.25)
			(net 283 "/Misc/TACH_{C5V}")
			(pinfunction "B_{1}")
			(pintype "bidirectional")
			(teardrops
				(best_length_ratio 0.2)
				(max_length 1)
				(best_width_ratio 0.9)
				(max_width 2)
				(curved_edges yes)
				(filter_ratio 0.9)
				(enabled yes)
				(allow_two_segments yes)
				(prefer_zone_connections yes)
			)
		)
	)
	(footprint "antmicro-footprints:TP_SMD_0.75mm"
		(layer "F.Cu")
		(at 146.6 128.71)
		(property "Reference" "TP74"
			(at 0.4 -3.3 90)
			(layer "F.SilkS")
			(effects
				(font
					(size 0.7 0.7)
					(thickness 0.15)
				)
				(justify left bottom)
			)
		)
		(property "Value" "TP_0.75mm_SMD"
			(at 0 1.2 0)
			(layer "F.Fab")
			(effects
				(font
					(size 0.7 0.7)
					(thickness 0.15)
				)
				(justify left bottom)
			)
		)
		(property "Author" "Antmicro"
			(at 0 0 0)
			(layer "F.Fab")
			(hide yes)
			(effects
				(font
					(size 1 1)
					(thickness 0.15)
				)
			)
		)
		(property "License" "Apache-2.0"
			(at 0 0 0)
			(layer "F.Fab")
			(hide yes)
			(effects
				(font
					(size 1 1)
					(thickness 0.15)
				)
			)
		)
		(property "MPN" ""
			(at 0 0 0)
			(layer "F.Fab")
			(hide yes)
			(effects
				(font
					(size 1 1)
					(thickness 0.15)
				)
			)
		)
		(property "Manufacturer" ""
			(at 0 0 0)
			(layer "F.Fab")
			(hide yes)
			(effects
				(font
					(size 1 1)
					(thickness 0.15)
				)
			)
		)
		(property "Public" "False"
			(at 0 0 0)
			(layer "F.Fab")
			(hide yes)
			(effects
				(font
					(size 1 1)
					(thickness 0.15)
				)
			)
		)
		(sheetname "KR to SFI #1")
		(sheetfile "kr_sfi.kicad_sch")
		(attr exclude_from_pos_files exclude_from_bom)
		(fp_circle
			(center 0 0)
			(end 0.475 0)
			(stroke
				(width 0.05)
				(type default)
			)
			(fill no)
			(layer "F.CrtYd")
		)
		(pad "1" smd circle
			(at 0 0)
			(size 0.75 0.75)
			(layers "F.Cu" "F.Mask")
			(net 737 "Net-(U43B-LOSB)")
			(pinfunction "1")
			(pintype "passive")
			(teardrops
				(best_length_ratio 0.4)
				(max_length 1)
				(best_width_ratio 0.9)
				(max_width 2)
				(curved_edges yes)
				(filter_ratio 0.9)
				(enabled yes)
				(allow_two_segments yes)
				(prefer_zone_connections yes)
			)
		)
	)
	(footprint "antmicro-footprints:R_0201"
		(layer "F.Cu")
		(at 134.41 147.31 90)
		(descr "Resistor SMD 0201")
		(tags "resistor SMD 0201")
		(property "Reference" "R291"
			(at -4.099 0.29 90)
			(layer "F.SilkS")
			(effects
				(font
					(size 0.7 0.7)
					(thickness 0.15)
				)
				(justify left bottom)
			)
		)
		(property "Value" "R_0R_0201"
			(at 0 1.25 90)
			(layer "F.Fab")
			(effects
				(font
					(size 0.7 0.7)
					(thickness 0.15)
				)
				(justify left bottom)
			)
		)
		(property "Datasheet" "https://www.bourns.com/docs/product-datasheets/cr.pdf"
			(at 0 0 90)
			(layer "F.Fab")
			(hide yes)
			(effects
				(font
					(size 1.27 1.27)
					(thickness 0.15)
				)
			)
		)
		(property "Author" "Antmicro"
			(at 281.72 12.9 0)
			(layer "F.Fab")
			(hide yes)
			(effects
				(font
					(size 1 1)
					(thickness 0.15)
				)
			)
		)
		(property "License" "Apache-2.0"
			(at 281.72 12.9 0)
			(layer "F.Fab")
			(hide yes)
			(effects
				(font
					(size 1 1)
					(thickness 0.15)
				)
			)
		)
		(property "MPN" "CR0201-FX-0R00GLF"
			(at 281.72 12.9 0)
			(layer "F.Fab")
			(hide yes)
			(effects
				(font
					(size 1 1)
					(thickness 0.15)
				)
			)
		)
		(property "Manufacturer" "Bourns"
			(at 281.72 12.9 0)
			(layer "F.Fab")
			(hide yes)
			(effects
				(font
					(size 1 1)
					(thickness 0.15)
				)
			)
		)
		(property "Tolerance" "1%"
			(at 281.72 12.9 0)
			(layer "F.Fab")
			(hide yes)
			(effects
				(font
					(size 1 1)
					(thickness 0.15)
				)
			)
		)
		(property "Val" "0R"
			(at 281.72 12.9 0)
			(layer "F.Fab")
			(hide yes)
			(effects
				(font
					(size 1 1)
					(thickness 0.15)
				)
			)
		)
		(sheetname "KR to SFI #2")
		(sheetfile "kr_sfi.kicad_sch")
		(attr smd)
		(fp_rect
			(start -0.7 -0.35)
			(end 0.7 0.35)
			(stroke
				(width 0.05)
				(type default)
			)
			(fill no)
			(layer "F.CrtYd")
		)
		(fp_rect
			(start -0.3 -0.15)
			(end 0.298 0.148)
			(stroke
				(width 0.15)
				(type solid)
			)
			(fill no)
			(layer "F.Fab")
		)
		(pad "" smd roundrect
			(at -0.346 0 90)
			(size 0.318 0.36)
			(layers "F.Paste")
			(roundrect_rratio 0.25)
			(teardrops
				(best_length_ratio 0.2)
				(max_length 1)
				(best_width_ratio 0.9)
				(max_width 2)
				(curved_edges yes)
				(filter_ratio 0.9)
				(enabled yes)
				(allow_two_segments yes)
				(prefer_zone_connections yes)
			)
		)
		(pad "" smd roundrect
			(at 0.344 0 90)
			(size 0.318 0.36)
			(layers "F.Paste")
			(roundrect_rratio 0.25)
			(teardrops
				(best_length_ratio 0.2)
				(max_length 1)
				(best_width_ratio 0.9)
				(max_width 2)
				(curved_edges yes)
				(filter_ratio 0.9)
				(enabled yes)
				(allow_two_segments yes)
				(prefer_zone_connections yes)
			)
		)
		(pad "1" smd roundrect
			(at -0.32 0 90)
			(size 0.46 0.4)
			(layers "F.Cu" "F.Mask")
			(roundrect_rratio 0.25)
			(net 428 "/2xSFP+/10GKR_SFP1.RX-")
			(pintype "passive")
			(teardrops
				(best_length_ratio 0.2)
				(max_length 1)
				(best_width_ratio 0.9)
				(max_width 2)
				(curved_edges yes)
				(filter_ratio 0.9)
				(enabled yes)
				(allow_two_segments yes)
				(prefer_zone_connections yes)
			)
		)
		(pad "2" smd roundrect
			(at 0.32 0 90)
			(size 0.46 0.4)
			(layers "F.Cu" "F.Mask")
			(roundrect_rratio 0.25)
			(net 688 "/2xSFP+/KR to SFI #2/KR_R.RX-")
			(pintype "passive")
			(teardrops
				(best_length_ratio 0.2)
				(max_length 1)
				(best_width_ratio 0.9)
				(max_width 2)
				(curved_edges yes)
				(filter_ratio 0.9)
				(enabled yes)
				(allow_two_segments yes)
				(prefer_zone_connections yes)
			)
		)
	)
	(footprint "antmicro-footprints:R_0402_1005Metric"
		(layer "F.Cu")
		(at 221.16 130.65)
		(descr "Resistor SMD 0402")
		(tags "resistor SMD 0402")
		(property "Reference" "R200"
			(at 0.79 0.41 0)
			(layer "F.SilkS")
			(effects
				(font
					(size 0.7 0.7)
					(thickness 0.15)
				)
				(justify left bottom)
			)
		)
		(property "Value" "R_0R_0402"
			(at -1.011843 1.772047 0)
			(layer "F.Fab")
			(effects
				(font
					(size 0.7 0.7)
					(thickness 0.15)
				)
				(justify left bottom)
			)
		)
		(property "Datasheet" "https://industrial.panasonic.com/cdbs/www-data/pdf/RDA0000/AOA0000C301.pdf"
			(at 0 0 0)
			(layer "F.Fab")
			(hide yes)
			(effects
				(font
					(size 1.27 1.27)
					(thickness 0.15)
				)
			)
		)
		(property "Author" "Antmicro"
			(at 0 0 0)
			(layer "F.Fab")
			(hide yes)
			(effects
				(font
					(size 1 1)
					(thickness 0.15)
				)
			)
		)
		(property "Current" "1A"
			(at 0 0 0)
			(layer "F.Fab")
			(hide yes)
			(effects
				(font
					(size 1 1)
					(thickness 0.15)
				)
			)
		)
		(property "License" "Apache-2.0"
			(at 0 0 0)
			(layer "F.Fab")
			(hide yes)
			(effects
				(font
					(size 1 1)
					(thickness 0.15)
				)
			)
		)
		(property "MPN" "ERJ2GE0R00X"
			(at 0 0 0)
			(layer "F.Fab")
			(hide yes)
			(effects
				(font
					(size 1 1)
					(thickness 0.15)
				)
			)
		)
		(property "Manufacturer" "Panasonic"
			(at 0 0 0)
			(layer "F.Fab")
			(hide yes)
			(effects
				(font
					(size 1 1)
					(thickness 0.15)
				)
			)
		)
		(property "Public" "False"
			(at 0 0 0)
			(layer "F.Fab")
			(hide yes)
			(effects
				(font
					(size 1 1)
					(thickness 0.15)
				)
			)
		)
		(property "Tolerance" ""
			(at 0 0 0)
			(layer "F.Fab")
			(hide yes)
			(effects
				(font
					(size 1 1)
					(thickness 0.15)
				)
			)
		)
		(property "Val" "0R"
			(at 0 0 0)
			(layer "F.Fab")
			(hide yes)
			(effects
				(font
					(size 1 1)
					(thickness 0.15)
				)
			)
		)
		(sheetname "PCIe misc")
		(sheetfile "pcie_misc.kicad_sch")
		(attr smd)
		(fp_rect
			(start -0.925 -0.47)
			(end 0.925 0.47)
			(stroke
				(width 0.05)
				(type default)
			)
			(fill no)
			(layer "F.CrtYd")
		)
		(fp_rect
			(start -0.5 -0.25)
			(end 0.5 0.25)
			(stroke
				(width 0.15)
				(type solid)
			)
			(fill no)
			(layer "F.Fab")
		)
		(pad "1" smd roundrect
			(at -0.48 0)
			(size 0.59 0.64)
			(layers "F.Cu" "F.Mask" "F.Paste")
			(roundrect_rratio 0.25)
			(net 619 "/PCIe misc/DIF4+")
			(pintype "passive")
			(teardrops
				(best_length_ratio 0.2)
				(max_length 1)
				(best_width_ratio 0.9)
				(max_width 2)
				(curved_edges yes)
				(filter_ratio 0.9)
				(enabled yes)
				(allow_two_segments yes)
				(prefer_zone_connections yes)
			)
		)
		(pad "2" smd roundrect
			(at 0.48 0)
			(size 0.59 0.64)
			(layers "F.Cu" "F.Mask" "F.Paste")
			(roundrect_rratio 0.25)
			(net 273 "/M.2 key M #2/PCIE_{REF}.CK+")
			(pintype "passive")
			(teardrops
				(best_length_ratio 0.2)
				(max_length 1)
				(best_width_ratio 0.9)
				(max_width 2)
				(curved_edges yes)
				(filter_ratio 0.9)
				(enabled yes)
				(allow_two_segments yes)
				(prefer_zone_connections yes)
			)
		)
	)
)
